# T6G (Grand Teton) — schematic netlist excerpt (pin names and nets, part order shuffled) for the footprints in the layout excerpt that follows; sources: Cadence DE-HDL packaged netlist, KiCad conversion of 04192023_DAF0TMB3IC0_F0TG_MB_C_brd_V02_OCP.brd

R2694  Q_RES  1K 1% CHIP  pkg 0402LF  page 245 : A = TCA9539_0_ADD1 ; B = GND
PR89  Q_RES  5.6 1% CHIP  pkg 0402LF  page 202 : A = SW_PVDDCR_CPU1_P0_BOOT4 ; B = SW_PVDDCR_CPU1_P0_BOOT4_R

(kicad_pcb
	(version 20260206)
	(generator "pcbnew")
	(generator_version "10.0")
	(general
		(thickness 1.6)
		(legacy_teardrops no)
	)
	(paper "A4")
	(title_block
		(title "04192023_DAF0TMB3IC0_F0TG_MB_C_brd_V02_OCP.brd")
		(comment 1 "Grand Teton / footprints 4740-4741 of 8354")
	)
	(layers
		(0 "F.Cu" signal "TOP")
		(4 "In1.Cu" signal "GND")
		(6 "In2.Cu" signal "IN1")
		(8 "In3.Cu" signal "GND1")
		(10 "In4.Cu" signal "IN2")
		(12 "In5.Cu" signal "GND2")
		(14 "In6.Cu" signal "IN3")
		(16 "In7.Cu" signal "GND3")
		(18 "In8.Cu" signal "VCC")
		(20 "In9.Cu" signal "VCC1")
		(22 "In10.Cu" signal "GND4")
		(24 "In11.Cu" signal "IN4")
		(26 "In12.Cu" signal "GND5")
		(28 "In13.Cu" signal "IN5")
		(30 "In14.Cu" signal "GND6")
		(32 "In15.Cu" signal "IN6")
		(34 "In16.Cu" signal "GND7")
		(2 "B.Cu" signal "BOTTOM")
		(9 "F.Adhes" user "F.Adhesive")
		(11 "B.Adhes" user "B.Adhesive")
		(13 "F.Paste" user "Package Geometry/Pastemask Top")
		(15 "B.Paste" user "Package Geometry/Pastemask Bottom")
		(5 "F.SilkS" user "Ref Des/Silkscreen Top")
		(7 "B.SilkS" user "Ref Des/Silkscreen Bottom")
		(1 "F.Mask" user "Board Geometry/Soldermask Top")
		(3 "B.Mask" user "Board Geometry/Soldermask Bottom")
		(17 "Dwgs.User" user "User.Drawings")
		(19 "Cmts.User" user "User.Comments")
		(21 "Eco1.User" user "User.Eco1")
		(23 "Eco2.User" user "User.Eco2")
		(25 "Edge.Cuts" user "Board Geometry/Outline")
		(27 "Margin" user)
		(31 "F.CrtYd" user "Package Geometry/Place Bound Top")
		(29 "B.CrtYd" user "Package Geometry/Place Bound Bottom")
		(35 "F.Fab" user "Ref Des/Assembly Top")
		(33 "B.Fab" user "Ref Des/Assembly Bottom")
	)
	(footprint ""
		(layer "F.Cu")
		(at 309.455312 -351.368106 90)
		(property "Reference" "PR89"
			(at 0 0 90)
			(layer "F.SilkS")
			(hide yes)
			(effects
				(font
					(size 1.27 1.27)
				)
			)
		)
		(property "Value" ""
			(at 0 0 90)
			(layer "F.Fab")
			(effects
				(font
					(size 1.27 1.27)
				)
			)
		)
		(duplicate_pad_numbers_are_jumpers no)
		(fp_line
			(start 0.7874 -0.4064)
			(end 0.7874 0.4064)
			(stroke
				(width 0.1524)
				(type default)
			)
			(layer "F.SilkS")
		)
		(fp_line
			(start -0.7874 -0.4064)
			(end 0.7874 -0.4064)
			(stroke
				(width 0.1524)
				(type default)
			)
			(layer "F.SilkS")
		)
		(fp_line
			(start 0.7874 0.4064)
			(end -0.7874 0.4064)
			(stroke
				(width 0.1524)
				(type default)
			)
			(layer "F.SilkS")
		)
		(fp_line
			(start -0.7874 0.4064)
			(end -0.7874 -0.4064)
			(stroke
				(width 0.1524)
				(type default)
			)
			(layer "F.SilkS")
		)
		(fp_line
			(start -0.12065 -0.305054)
			(end -0.12065 -0.2794)
			(stroke
				(width 0.1)
				(type default)
			)
			(layer "F.Fab")
		)
		(fp_line
			(start -0.67945 -0.305054)
			(end -0.12065 -0.305054)
			(stroke
				(width 0.1)
				(type default)
			)
			(layer "F.Fab")
		)
		(fp_line
			(start 0.67945 -0.3048)
			(end 0.67945 0.3048)
			(stroke
				(width 0.1)
				(type default)
			)
			(layer "F.Fab")
		)
		(fp_line
			(start 0.12065 -0.3048)
			(end 0.67945 -0.3048)
			(stroke
				(width 0.1)
				(type default)
			)
			(layer "F.Fab")
		)
		(fp_line
			(start 0.12065 -0.2794)
			(end 0.12065 -0.3048)
			(stroke
				(width 0.1)
				(type default)
			)
			(layer "F.Fab")
		)
		(fp_line
			(start -0.12065 -0.2794)
			(end 0.12065 -0.2794)
			(stroke
				(width 0.1)
				(type default)
			)
			(layer "F.Fab")
		)
		(fp_line
			(start 0.120396 0.2794)
			(end -0.12065 0.2794)
			(stroke
				(width 0.1)
				(type default)
			)
			(layer "F.Fab")
		)
		(fp_line
			(start -0.12065 0.2794)
			(end -0.12065 0.3048)
			(stroke
				(width 0.1)
				(type default)
			)
			(layer "F.Fab")
		)
		(fp_line
			(start 0.67945 0.3048)
			(end 0.120396 0.3048)
			(stroke
				(width 0.1)
				(type default)
			)
			(layer "F.Fab")
		)
		(fp_line
			(start 0.120396 0.3048)
			(end 0.120396 0.2794)
			(stroke
				(width 0.1)
				(type default)
			)
			(layer "F.Fab")
		)
		(fp_line
			(start -0.12065 0.3048)
			(end -0.67945 0.3048)
			(stroke
				(width 0.1)
				(type default)
			)
			(layer "F.Fab")
		)
		(fp_line
			(start -0.67945 0.3048)
			(end -0.67945 -0.305054)
			(stroke
				(width 0.1)
				(type default)
			)
			(layer "F.Fab")
		)
		(pad "1" smd circle
			(at -0.40005 0 90)
			(size 0 0)
			(layers "F.Cu" "F.Mask" "F.Paste")
			(net "SW_PVDDCR_CPU1_P0_BOOT4")
		)
		(pad "2" smd circle
			(at 0.40005 0 90)
			(size 0 0)
			(layers "F.Cu" "F.Mask" "F.Paste")
			(net "SW_PVDDCR_CPU1_P0_BOOT4_R")
		)
	)
	(footprint ""
		(layer "F.Cu")
		(at 178.764946 -413.815022 -90)
		(property "Reference" "R2694"
			(at 0 0 270)
			(layer "F.SilkS")
			(hide yes)
			(effects
				(font
					(size 1.27 1.27)
				)
			)
		)
		(property "Value" ""
			(at 0 0 270)
			(layer "F.Fab")
			(effects
				(font
					(size 1.27 1.27)
				)
			)
		)
		(duplicate_pad_numbers_are_jumpers no)
		(fp_line
			(start -0.7874 0.4064)
			(end -0.7874 -0.4064)
			(stroke
				(width 0.1524)
				(type default)
			)
			(layer "F.SilkS")
		)
		(fp_line
			(start 0.7874 0.4064)
			(end -0.7874 0.4064)
			(stroke
				(width 0.1524)
				(type default)
			)
			(layer "F.SilkS")
		)
		(fp_line
			(start -0.7874 -0.4064)
			(end 0.7874 -0.4064)
			(stroke
				(width 0.1524)
				(type default)
			)
			(layer "F.SilkS")
		)
		(fp_line
			(start 0.7874 -0.4064)
			(end 0.7874 0.4064)
			(stroke
				(width 0.1524)
				(type default)
			)
			(layer "F.SilkS")
		)
		(fp_line
			(start -0.67945 0.3048)
			(end -0.67945 -0.305054)
			(stroke
				(width 0.1)
				(type default)
			)
			(layer "F.Fab")
		)
		(fp_line
			(start -0.12065 0.3048)
			(end -0.67945 0.3048)
			(stroke
				(width 0.1)
				(type default)
			)
			(layer "F.Fab")
		)
		(fp_line
			(start 0.120396 0.3048)
			(end 0.120396 0.2794)
			(stroke
				(width 0.1)
				(type default)
			)
			(layer "F.Fab")
		)
		(fp_line
			(start 0.67945 0.3048)
			(end 0.120396 0.3048)
			(stroke
				(width 0.1)
				(type default)
			)
			(layer "F.Fab")
		)
		(fp_line
			(start -0.12065 0.2794)
			(end -0.12065 0.3048)
			(stroke
				(width 0.1)
				(type default)
			)
			(layer "F.Fab")
		)
		(fp_line
			(start 0.120396 0.2794)
			(end -0.12065 0.2794)
			(stroke
				(width 0.1)
				(type default)
			)
			(layer "F.Fab")
		)
		(fp_line
			(start -0.12065 -0.2794)
			(end 0.12065 -0.2794)
			(stroke
				(width 0.1)
				(type default)
			)
			(layer "F.Fab")
		)
		(fp_line
			(start 0.12065 -0.2794)
			(end 0.12065 -0.3048)
			(stroke
				(width 0.1)
				(type default)
			)
			(layer "F.Fab")
		)
		(fp_line
			(start 0.12065 -0.3048)
			(end 0.67945 -0.3048)
			(stroke
				(width 0.1)
				(type default)
			)
			(layer "F.Fab")
		)
		(fp_line
			(start 0.67945 -0.3048)
			(end 0.67945 0.3048)
			(stroke
				(width 0.1)
				(type default)
			)
			(layer "F.Fab")
		)
		(fp_line
			(start -0.67945 -0.305054)
			(end -0.12065 -0.305054)
			(stroke
				(width 0.1)
				(type default)
			)
			(layer "F.Fab")
		)
		(fp_line
			(start -0.12065 -0.305054)
			(end -0.12065 -0.2794)
			(stroke
				(width 0.1)
				(type default)
			)
			(layer "F.Fab")
		)
		(pad "1" smd circle
			(at -0.40005 0 270)
			(size 0 0)
			(layers "F.Cu" "F.Mask" "F.Paste")
			(net "TCA9539_0_ADD1")
		)
		(pad "2" smd circle
			(at 0.40005 0 270)
			(size 0 0)
			(layers "F.Cu" "F.Mask" "F.Paste")
			(net "GND")
		)
	)
)
